(kicad_pcb
	(version 20260206)
	(generator "pcbnew")
	(generator_version "10.0")
	(general
		(thickness 1.6)
		(legacy_teardrops no)
	)
	(paper "A4")
	(title_block
		(title "04192023_DAF0TMB3IC0_F0TG_MB_C_brd_V02_OCP.brd")
		(comment 1 "Grand Teton / footprints 8305-8312 of 8354")
	)
	(layers
		(0 "F.Cu" signal "TOP")
		(4 "In1.Cu" signal "GND")
		(6 "In2.Cu" signal "IN1")
		(8 "In3.Cu" signal "GND1")
		(10 "In4.Cu" signal "IN2")
		(12 "In5.Cu" signal "GND2")
		(14 "In6.Cu" signal "IN3")
		(16 "In7.Cu" signal "GND3")
		(18 "In8.Cu" signal "VCC")
		(20 "In9.Cu" signal "VCC1")
		(22 "In10.Cu" signal "GND4")
		(24 "In11.Cu" signal "IN4")
		(26 "In12.Cu" signal "GND5")
		(28 "In13.Cu" signal "IN5")
		(30 "In14.Cu" signal "GND6")
		(32 "In15.Cu" signal "IN6")
		(34 "In16.Cu" signal "GND7")
		(2 "B.Cu" signal "BOTTOM")
		(9 "F.Adhes" user "F.Adhesive")
		(11 "B.Adhes" user "B.Adhesive")
		(13 "F.Paste" user "Package Geometry/Pastemask Top")
		(15 "B.Paste" user "Package Geometry/Pastemask Bottom")
		(5 "F.SilkS" user "Ref Des/Silkscreen Top")
		(7 "B.SilkS" user "Ref Des/Silkscreen Bottom")
		(1 "F.Mask" user "Board Geometry/Soldermask Top")
		(3 "B.Mask" user "Board Geometry/Soldermask Bottom")
		(17 "Dwgs.User" user "User.Drawings")
		(19 "Cmts.User" user "User.Comments")
		(21 "Eco1.User" user "User.Eco1")
		(23 "Eco2.User" user "User.Eco2")
		(25 "Edge.Cuts" user "Board Geometry/Outline")
		(27 "Margin" user)
		(31 "F.CrtYd" user "Package Geometry/Place Bound Top")
		(29 "B.CrtYd" user "Package Geometry/Place Bound Bottom")
		(35 "F.Fab" user "Ref Des/Assembly Top")
		(33 "B.Fab" user "Ref Des/Assembly Bottom")
	)
	(footprint ""
		(layer "B.Cu")
		(at 450.84365 -194.88531 180)
		(property "Reference" "R769"
			(at 0 0 0)
			(layer "B.SilkS")
			(hide yes)
			(effects
				(font
					(size 1.27 1.27)
				)
				(justify mirror)
			)
		)
		(property "Value" ""
			(at 0 0 0)
			(layer "B.Fab")
			(effects
				(font
					(size 1.27 1.27)
				)
				(justify mirror)
			)
		)
		(duplicate_pad_numbers_are_jumpers no)
		(fp_line
			(start 0.7874 0.4064)
			(end 0.7874 -0.4064)
			(stroke
				(width 0.1524)
				(type default)
			)
			(layer "B.SilkS")
		)
		(fp_line
			(start 0.7874 -0.4064)
			(end -0.7874 -0.4064)
			(stroke
				(width 0.1524)
				(type default)
			)
			(layer "B.SilkS")
		)
		(fp_line
			(start -0.7874 0.4064)
			(end 0.7874 0.4064)
			(stroke
				(width 0.1524)
				(type default)
			)
			(layer "B.SilkS")
		)
		(fp_line
			(start -0.7874 -0.4064)
			(end -0.7874 0.4064)
			(stroke
				(width 0.1524)
				(type default)
			)
			(layer "B.SilkS")
		)
		(fp_line
			(start 0.67945 0.3048)
			(end 0.67945 -0.305054)
			(stroke
				(width 0.1)
				(type default)
			)
			(layer "B.Fab")
		)
		(fp_line
			(start 0.67945 -0.305054)
			(end 0.12065 -0.305054)
			(stroke
				(width 0.1)
				(type default)
			)
			(layer "B.Fab")
		)
		(fp_line
			(start 0.12065 0.3048)
			(end 0.67945 0.3048)
			(stroke
				(width 0.1)
				(type default)
			)
			(layer "B.Fab")
		)
		(fp_line
			(start 0.12065 0.2794)
			(end 0.12065 0.3048)
			(stroke
				(width 0.1)
				(type default)
			)
			(layer "B.Fab")
		)
		(fp_line
			(start 0.12065 -0.2794)
			(end -0.12065 -0.2794)
			(stroke
				(width 0.1)
				(type default)
			)
			(layer "B.Fab")
		)
		(fp_line
			(start 0.12065 -0.305054)
			(end 0.12065 -0.2794)
			(stroke
				(width 0.1)
				(type default)
			)
			(layer "B.Fab")
		)
		(fp_line
			(start -0.120396 0.3048)
			(end -0.120396 0.2794)
			(stroke
				(width 0.1)
				(type default)
			)
			(layer "B.Fab")
		)
		(fp_line
			(start -0.120396 0.2794)
			(end 0.12065 0.2794)
			(stroke
				(width 0.1)
				(type default)
			)
			(layer "B.Fab")
		)
		(fp_line
			(start -0.12065 -0.2794)
			(end -0.12065 -0.3048)
			(stroke
				(width 0.1)
				(type default)
			)
			(layer "B.Fab")
		)
		(fp_line
			(start -0.12065 -0.3048)
			(end -0.67945 -0.3048)
			(stroke
				(width 0.1)
				(type default)
			)
			(layer "B.Fab")
		)
		(fp_line
			(start -0.67945 0.3048)
			(end -0.120396 0.3048)
			(stroke
				(width 0.1)
				(type default)
			)
			(layer "B.Fab")
		)
		(fp_line
			(start -0.67945 -0.3048)
			(end -0.67945 0.3048)
			(stroke
				(width 0.1)
				(type default)
			)
			(layer "B.Fab")
		)
		(pad "1" smd circle
			(at 0.40005 0)
			(size 0 0)
			(layers "B.Cu" "B.Mask" "B.Paste")
			(net "PD_CHL_CPU0_DIMM_SAA")
		)
		(pad "2" smd circle
			(at -0.40005 0)
			(size 0 0)
			(layers "B.Cu" "B.Mask" "B.Paste")
			(net "GND")
		)
	)
	(footprint ""
		(layer "B.Cu")
		(at 446.258442 -53.188108 -90)
		(property "Reference" "PC8014"
			(at 0 0 90)
			(layer "B.SilkS")
			(hide yes)
			(effects
				(font
					(size 1.27 1.27)
				)
				(justify mirror)
			)
		)
		(property "Value" ""
			(at 0 0 90)
			(layer "B.Fab")
			(effects
				(font
					(size 1.27 1.27)
				)
				(justify mirror)
			)
		)
		(duplicate_pad_numbers_are_jumpers no)
		(fp_line
			(start -1.524 0.762)
			(end 1.524 0.762)
			(stroke
				(width 0.1524)
				(type default)
			)
			(layer "B.SilkS")
		)
		(fp_line
			(start 1.524 0.762)
			(end 1.524 -0.762)
			(stroke
				(width 0.1524)
				(type default)
			)
			(layer "B.SilkS")
		)
		(fp_line
			(start -1.524 -0.762)
			(end -1.524 0.762)
			(stroke
				(width 0.1524)
				(type default)
			)
			(layer "B.SilkS")
		)
		(fp_line
			(start 1.524 -0.762)
			(end -1.524 -0.762)
			(stroke
				(width 0.1524)
				(type default)
			)
			(layer "B.SilkS")
		)
		(fp_line
			(start -1.1049 0.724916)
			(end -1.1049 -0.724916)
			(stroke
				(width 0.1)
				(type default)
			)
			(layer "B.Fab")
		)
		(fp_line
			(start 1.1049 0.724916)
			(end -1.1049 0.724916)
			(stroke
				(width 0.1)
				(type default)
			)
			(layer "B.Fab")
		)
		(fp_line
			(start -1.1049 -0.724916)
			(end 1.1049 -0.724916)
			(stroke
				(width 0.1)
				(type default)
			)
			(layer "B.Fab")
		)
		(fp_line
			(start 1.1049 -0.724916)
			(end 1.1049 0.724916)
			(stroke
				(width 0.1)
				(type default)
			)
			(layer "B.Fab")
		)
		(pad "1" smd rect
			(at 0.889 0 270)
			(size 1.016 1.27)
			(layers "B.Cu" "B.Mask" "B.Paste")
			(net "SW_P3V3_AUX_FLT")
		)
		(pad "2" smd rect
			(at -0.889 0 270)
			(size 1.016 1.27)
			(layers "B.Cu" "B.Mask" "B.Paste")
			(net "GND")
		)
	)
	(footprint ""
		(layer "B.Cu")
		(at 411.40634 -395.148562 90)
		(property "Reference" "C774"
			(at 0 0 90)
			(layer "B.SilkS")
			(hide yes)
			(effects
				(font
					(size 1.27 1.27)
				)
				(justify mirror)
			)
		)
		(property "Value" ""
			(at 0 0 90)
			(layer "B.Fab")
			(effects
				(font
					(size 1.27 1.27)
				)
				(justify mirror)
			)
		)
		(duplicate_pad_numbers_are_jumpers no)
		(fp_line
			(start 0.299974 -0.150114)
			(end -0.299974 -0.150114)
			(stroke
				(width 0.1)
				(type default)
			)
			(layer "B.Fab")
		)
		(fp_line
			(start -0.299974 -0.150114)
			(end -0.299974 0.150114)
			(stroke
				(width 0.1)
				(type default)
			)
			(layer "B.Fab")
		)
		(fp_line
			(start 0.299974 0.150114)
			(end 0.299974 -0.150114)
			(stroke
				(width 0.1)
				(type default)
			)
			(layer "B.Fab")
		)
		(fp_line
			(start -0.299974 0.150114)
			(end 0.299974 0.150114)
			(stroke
				(width 0.1)
				(type default)
			)
			(layer "B.Fab")
		)
		(pad "1" smd rect
			(at 0.2667 0 270)
			(size 0.3048 0.381)
			(layers "B.Cu" "B.Mask" "B.Paste")
			(net "P1V8_CPU0_RT2_1A")
		)
		(pad "2" smd rect
			(at -0.2667 0 270)
			(size 0.3048 0.381)
			(layers "B.Cu" "B.Mask" "B.Paste")
			(net "GND")
		)
	)
	(footprint ""
		(layer "B.Cu")
		(at 57.118504 -388.011162 -90)
		(property "Reference" "C129"
			(at 0 0 90)
			(layer "B.SilkS")
			(hide yes)
			(effects
				(font
					(size 1.27 1.27)
				)
				(justify mirror)
			)
		)
		(property "Value" ""
			(at 0 0 90)
			(layer "B.Fab")
			(effects
				(font
					(size 1.27 1.27)
				)
				(justify mirror)
			)
		)
		(duplicate_pad_numbers_are_jumpers no)
		(fp_line
			(start -0.299974 0.150114)
			(end 0.299974 0.150114)
			(stroke
				(width 0.1)
				(type default)
			)
			(layer "B.Fab")
		)
		(fp_line
			(start 0.299974 0.150114)
			(end 0.299974 -0.150114)
			(stroke
				(width 0.1)
				(type default)
			)
			(layer "B.Fab")
		)
		(fp_line
			(start -0.299974 -0.150114)
			(end -0.299974 0.150114)
			(stroke
				(width 0.1)
				(type default)
			)
			(layer "B.Fab")
		)
		(fp_line
			(start 0.299974 -0.150114)
			(end -0.299974 -0.150114)
			(stroke
				(width 0.1)
				(type default)
			)
			(layer "B.Fab")
		)
		(pad "1" smd rect
			(at 0.2667 0 90)
			(size 0.3048 0.381)
			(layers "B.Cu" "B.Mask" "B.Paste")
			(net "P1V8_CPU1_RT0_1A")
		)
		(pad "2" smd rect
			(at -0.2667 0 90)
			(size 0.3048 0.381)
			(layers "B.Cu" "B.Mask" "B.Paste")
			(net "GND")
		)
	)
	(footprint ""
		(layer "B.Cu")
		(at 46.359318 -431.985674 -90)
		(property "Reference" "R3432"
			(at 0 0 90)
			(layer "B.SilkS")
			(hide yes)
			(effects
				(font
					(size 1.27 1.27)
				)
				(justify mirror)
			)
		)
		(property "Value" ""
			(at 0 0 90)
			(layer "B.Fab")
			(effects
				(font
					(size 1.27 1.27)
				)
				(justify mirror)
			)
		)
		(duplicate_pad_numbers_are_jumpers no)
		(fp_line
			(start -0.7874 0.4064)
			(end 0.7874 0.4064)
			(stroke
				(width 0.1524)
				(type default)
			)
			(layer "B.SilkS")
		)
		(fp_line
			(start 0.7874 0.4064)
			(end 0.7874 -0.4064)
			(stroke
				(width 0.1524)
				(type default)
			)
			(layer "B.SilkS")
		)
		(fp_line
			(start -0.7874 -0.4064)
			(end -0.7874 0.4064)
			(stroke
				(width 0.1524)
				(type default)
			)
			(layer "B.SilkS")
		)
		(fp_line
			(start 0.7874 -0.4064)
			(end -0.7874 -0.4064)
			(stroke
				(width 0.1524)
				(type default)
			)
			(layer "B.SilkS")
		)
		(fp_line
			(start -0.67945 0.3048)
			(end -0.120396 0.3048)
			(stroke
				(width 0.1)
				(type default)
			)
			(layer "B.Fab")
		)
		(fp_line
			(start -0.120396 0.3048)
			(end -0.120396 0.2794)
			(stroke
				(width 0.1)
				(type default)
			)
			(layer "B.Fab")
		)
		(fp_line
			(start 0.12065 0.3048)
			(end 0.67945 0.3048)
			(stroke
				(width 0.1)
				(type default)
			)
			(layer "B.Fab")
		)
		(fp_line
			(start 0.67945 0.3048)
			(end 0.67945 -0.305054)
			(stroke
				(width 0.1)
				(type default)
			)
			(layer "B.Fab")
		)
		(fp_line
			(start -0.120396 0.2794)
			(end 0.12065 0.2794)
			(stroke
				(width 0.1)
				(type default)
			)
			(layer "B.Fab")
		)
		(fp_line
			(start 0.12065 0.2794)
			(end 0.12065 0.3048)
			(stroke
				(width 0.1)
				(type default)
			)
			(layer "B.Fab")
		)
		(fp_line
			(start -0.12065 -0.2794)
			(end -0.12065 -0.3048)
			(stroke
				(width 0.1)
				(type default)
			)
			(layer "B.Fab")
		)
		(fp_line
			(start 0.12065 -0.2794)
			(end -0.12065 -0.2794)
			(stroke
				(width 0.1)
				(type default)
			)
			(layer "B.Fab")
		)
		(fp_line
			(start -0.67945 -0.3048)
			(end -0.67945 0.3048)
			(stroke
				(width 0.1)
				(type default)
			)
			(layer "B.Fab")
		)
		(fp_line
			(start -0.12065 -0.3048)
			(end -0.67945 -0.3048)
			(stroke
				(width 0.1)
				(type default)
			)
			(layer "B.Fab")
		)
		(fp_line
			(start 0.12065 -0.305054)
			(end 0.12065 -0.2794)
			(stroke
				(width 0.1)
				(type default)
			)
			(layer "B.Fab")
		)
		(fp_line
			(start 0.67945 -0.305054)
			(end 0.12065 -0.305054)
			(stroke
				(width 0.1)
				(type default)
			)
			(layer "B.Fab")
		)
		(pad "1" smd circle
			(at 0.40005 0 90)
			(size 0 0)
			(layers "B.Cu" "B.Mask" "B.Paste")
			(net "P3V3_AUX")
		)
		(pad "2" smd circle
			(at -0.40005 0 90)
			(size 0 0)
			(layers "B.Cu" "B.Mask" "B.Paste")
			(net "GPU_FPGA_THERM_OVERT")
		)
	)
	(footprint ""
		(layer "B.Cu")
		(at 152.202642 -74.67854)
		(property "Reference" "PC866"
			(at 0 0 0)
			(layer "B.SilkS")
			(hide yes)
			(effects
				(font
					(size 1.27 1.27)
				)
				(justify mirror)
			)
		)
		(property "Value" ""
			(at 0 0 0)
			(layer "B.Fab")
			(effects
				(font
					(size 1.27 1.27)
				)
				(justify mirror)
			)
		)
		(duplicate_pad_numbers_are_jumpers no)
		(fp_line
			(start -1.524 -0.762)
			(end -1.524 0.762)
			(stroke
				(width 0.1524)
				(type default)
			)
			(layer "B.SilkS")
		)
		(fp_line
			(start -1.524 0.762)
			(end 1.524 0.762)
			(stroke
				(width 0.1524)
				(type default)
			)
			(layer "B.SilkS")
		)
		(fp_line
			(start 1.524 -0.762)
			(end -1.524 -0.762)
			(stroke
				(width 0.1524)
				(type default)
			)
			(layer "B.SilkS")
		)
		(fp_line
			(start 1.524 0.762)
			(end 1.524 -0.762)
			(stroke
				(width 0.1524)
				(type default)
			)
			(layer "B.SilkS")
		)
		(fp_line
			(start -1.1049 -0.724916)
			(end 1.1049 -0.724916)
			(stroke
				(width 0.1)
				(type default)
			)
			(layer "B.Fab")
		)
		(fp_line
			(start -1.1049 0.724916)
			(end -1.1049 -0.724916)
			(stroke
				(width 0.1)
				(type default)
			)
			(layer "B.Fab")
		)
		(fp_line
			(start 1.1049 -0.724916)
			(end 1.1049 0.724916)
			(stroke
				(width 0.1)
				(type default)
			)
			(layer "B.Fab")
		)
		(fp_line
			(start 1.1049 0.724916)
			(end -1.1049 0.724916)
			(stroke
				(width 0.1)
				(type default)
			)
			(layer "B.Fab")
		)
		(pad "1" smd rect
			(at 0.889 0)
			(size 1.016 1.27)
			(layers "B.Cu" "B.Mask" "B.Paste")
			(net "P1V8_AUX")
		)
		(pad "2" smd rect
			(at -0.889 0)
			(size 1.016 1.27)
			(layers "B.Cu" "B.Mask" "B.Paste")
			(net "GND")
		)
	)
	(footprint ""
		(layer "B.Cu")
		(at 173.301914 -13.416788 -90)
		(property "Reference" "R1460"
			(at 0 0 90)
			(layer "B.SilkS")
			(hide yes)
			(effects
				(font
					(size 1.27 1.27)
				)
				(justify mirror)
			)
		)
		(property "Value" ""
			(at 0 0 90)
			(layer "B.Fab")
			(effects
				(font
					(size 1.27 1.27)
				)
				(justify mirror)
			)
		)
		(duplicate_pad_numbers_are_jumpers no)
		(fp_line
			(start -0.7874 0.4064)
			(end 0.7874 0.4064)
			(stroke
				(width 0.1524)
				(type default)
			)
			(layer "B.SilkS")
		)
		(fp_line
			(start 0.7874 0.4064)
			(end 0.7874 -0.4064)
			(stroke
				(width 0.1524)
				(type default)
			)
			(layer "B.SilkS")
		)
		(fp_line
			(start -0.7874 -0.4064)
			(end -0.7874 0.4064)
			(stroke
				(width 0.1524)
				(type default)
			)
			(layer "B.SilkS")
		)
		(fp_line
			(start 0.7874 -0.4064)
			(end -0.7874 -0.4064)
			(stroke
				(width 0.1524)
				(type default)
			)
			(layer "B.SilkS")
		)
		(fp_line
			(start -0.67945 0.3048)
			(end -0.120396 0.3048)
			(stroke
				(width 0.1)
				(type default)
			)
			(layer "B.Fab")
		)
		(fp_line
			(start -0.120396 0.3048)
			(end -0.120396 0.2794)
			(stroke
				(width 0.1)
				(type default)
			)
			(layer "B.Fab")
		)
		(fp_line
			(start 0.12065 0.3048)
			(end 0.67945 0.3048)
			(stroke
				(width 0.1)
				(type default)
			)
			(layer "B.Fab")
		)
		(fp_line
			(start 0.67945 0.3048)
			(end 0.67945 -0.305054)
			(stroke
				(width 0.1)
				(type default)
			)
			(layer "B.Fab")
		)
		(fp_line
			(start -0.120396 0.2794)
			(end 0.12065 0.2794)
			(stroke
				(width 0.1)
				(type default)
			)
			(layer "B.Fab")
		)
		(fp_line
			(start 0.12065 0.2794)
			(end 0.12065 0.3048)
			(stroke
				(width 0.1)
				(type default)
			)
			(layer "B.Fab")
		)
		(fp_line
			(start -0.12065 -0.2794)
			(end -0.12065 -0.3048)
			(stroke
				(width 0.1)
				(type default)
			)
			(layer "B.Fab")
		)
		(fp_line
			(start 0.12065 -0.2794)
			(end -0.12065 -0.2794)
			(stroke
				(width 0.1)
				(type default)
			)
			(layer "B.Fab")
		)
		(fp_line
			(start -0.67945 -0.3048)
			(end -0.67945 0.3048)
			(stroke
				(width 0.1)
				(type default)
			)
			(layer "B.Fab")
		)
		(fp_line
			(start -0.12065 -0.3048)
			(end -0.67945 -0.3048)
			(stroke
				(width 0.1)
				(type default)
			)
			(layer "B.Fab")
		)
		(fp_line
			(start 0.12065 -0.305054)
			(end 0.12065 -0.2794)
			(stroke
				(width 0.1)
				(type default)
			)
			(layer "B.Fab")
		)
		(fp_line
			(start 0.67945 -0.305054)
			(end 0.12065 -0.305054)
			(stroke
				(width 0.1)
				(type default)
			)
			(layer "B.Fab")
		)
		(pad "1" smd circle
			(at 0.40005 0 90)
			(size 0 0)
			(layers "B.Cu" "B.Mask" "B.Paste")
			(net "I3C_BMC_SWB_SDA")
		)
		(pad "2" smd circle
			(at -0.40005 0 90)
			(size 0 0)
			(layers "B.Cu" "B.Mask" "B.Paste")
			(net "P3V3_AUX")
		)
	)
	(footprint ""
		(layer "B.Cu")
		(at 55.426864 -408.517344 90)
		(property "Reference" "C6666"
			(at 0 0 90)
			(layer "B.SilkS")
			(hide yes)
			(effects
				(font
					(size 1.27 1.27)
				)
				(justify mirror)
			)
		)
		(property "Value" ""
			(at 0 0 90)
			(layer "B.Fab")
			(effects
				(font
					(size 1.27 1.27)
				)
				(justify mirror)
			)
		)
		(duplicate_pad_numbers_are_jumpers no)
		(fp_line
			(start 0.299974 -0.150114)
			(end -0.299974 -0.150114)
			(stroke
				(width 0.1)
				(type default)
			)
			(layer "B.Fab")
		)
		(fp_line
			(start -0.299974 -0.150114)
			(end -0.299974 0.150114)
			(stroke
				(width 0.1)
				(type default)
			)
			(layer "B.Fab")
		)
		(fp_line
			(start 0.299974 0.150114)
			(end 0.299974 -0.150114)
			(stroke
				(width 0.1)
				(type default)
			)
			(layer "B.Fab")
		)
		(fp_line
			(start -0.299974 0.150114)
			(end 0.299974 0.150114)
			(stroke
				(width 0.1)
				(type default)
			)
			(layer "B.Fab")
		)
		(pad "1" smd rect
			(at 0.2667 0 270)
			(size 0.3048 0.381)
			(layers "B.Cu" "B.Mask" "B.Paste")
			(net "P5E_CPU1_P1_TX_BUF_C_DN<2>")
		)
		(pad "2" smd rect
			(at -0.2667 0 270)
			(size 0.3048 0.381)
			(layers "B.Cu" "B.Mask" "B.Paste")
			(net "P5E_CPU1_P1_TX_BUF_DN<2>")
		)
	)
)
